(kicad_pcb
	(version 20260206)
	(generator "pcbnew")
	(generator_version "10.0")
	(general
		(thickness 1.6)
		(legacy_teardrops no)
	)
	(paper "A4")
	(title_block
		(title "03242023_DA0F0TMBIJ0_F0T_Motherboard_J_brd_V01_OCP.brd")
		(comment 1 "Grand Teton / footprints 785-790 of 6105")
	)
	(layers
		(0 "F.Cu" signal "TOP")
		(4 "In1.Cu" signal "GND")
		(6 "In2.Cu" signal "IN1")
		(8 "In3.Cu" signal "GND1")
		(10 "In4.Cu" signal "IN2")
		(12 "In5.Cu" signal "GND2")
		(14 "In6.Cu" signal "IN3")
		(16 "In7.Cu" signal "GND3")
		(18 "In8.Cu" signal "VCC")
		(20 "In9.Cu" signal "VCC1")
		(22 "In10.Cu" signal "GND4")
		(24 "In11.Cu" signal "IN4")
		(26 "In12.Cu" signal "GND5")
		(28 "In13.Cu" signal "IN5")
		(30 "In14.Cu" signal "GND6")
		(32 "In15.Cu" signal "IN6")
		(34 "In16.Cu" signal "GND7")
		(2 "B.Cu" signal "BOTTOM")
		(9 "F.Adhes" user "F.Adhesive")
		(11 "B.Adhes" user "B.Adhesive")
		(13 "F.Paste" user "Package Geometry/Pastemask Top")
		(15 "B.Paste" user "Package Geometry/Pastemask Bottom")
		(5 "F.SilkS" user "Ref Des/Silkscreen Top")
		(7 "B.SilkS" user "Ref Des/Silkscreen Bottom")
		(1 "F.Mask" user "Board Geometry/Soldermask Top")
		(3 "B.Mask" user "Board Geometry/Soldermask Bottom")
		(17 "Dwgs.User" user "User.Drawings")
		(19 "Cmts.User" user "User.Comments")
		(21 "Eco1.User" user "User.Eco1")
		(23 "Eco2.User" user "User.Eco2")
		(25 "Edge.Cuts" user "Board Geometry/Outline")
		(27 "Margin" user)
		(31 "F.CrtYd" user "Package Geometry/Place Bound Top")
		(29 "B.CrtYd" user "Package Geometry/Place Bound Bottom")
		(35 "F.Fab" user "Ref Des/Assembly Top")
		(33 "B.Fab" user "Ref Des/Assembly Bottom")
	)
	(footprint ""
		(layer "F.Cu")
		(at 54.242716 -112.96269 180)
		(property "Reference" "R3713"
			(at 0 0 180)
			(layer "F.SilkS")
			(hide yes)
			(effects
				(font
					(size 1.27 1.27)
				)
			)
		)
		(property "Value" ""
			(at 0 0 180)
			(layer "F.Fab")
			(effects
				(font
					(size 1.27 1.27)
				)
			)
		)
		(duplicate_pad_numbers_are_jumpers no)
		(fp_line
			(start 0.7874 0.4064)
			(end -0.7874 0.4064)
			(stroke
				(width 0.1524)
				(type default)
			)
			(layer "F.SilkS")
		)
		(fp_line
			(start 0.7874 -0.4064)
			(end 0.7874 0.4064)
			(stroke
				(width 0.1524)
				(type default)
			)
			(layer "F.SilkS")
		)
		(fp_line
			(start -0.7874 0.4064)
			(end -0.7874 -0.4064)
			(stroke
				(width 0.1524)
				(type default)
			)
			(layer "F.SilkS")
		)
		(fp_line
			(start -0.7874 -0.4064)
			(end 0.7874 -0.4064)
			(stroke
				(width 0.1524)
				(type default)
			)
			(layer "F.SilkS")
		)
		(fp_line
			(start 0.67945 0.3048)
			(end 0.120396 0.3048)
			(stroke
				(width 0.1)
				(type default)
			)
			(layer "F.Fab")
		)
		(fp_line
			(start 0.67945 -0.3048)
			(end 0.67945 0.3048)
			(stroke
				(width 0.1)
				(type default)
			)
			(layer "F.Fab")
		)
		(fp_line
			(start 0.12065 -0.2794)
			(end 0.12065 -0.3048)
			(stroke
				(width 0.1)
				(type default)
			)
			(layer "F.Fab")
		)
		(fp_line
			(start 0.12065 -0.3048)
			(end 0.67945 -0.3048)
			(stroke
				(width 0.1)
				(type default)
			)
			(layer "F.Fab")
		)
		(fp_line
			(start 0.120396 0.3048)
			(end 0.120396 0.2794)
			(stroke
				(width 0.1)
				(type default)
			)
			(layer "F.Fab")
		)
		(fp_line
			(start 0.120396 0.2794)
			(end -0.12065 0.2794)
			(stroke
				(width 0.1)
				(type default)
			)
			(layer "F.Fab")
		)
		(fp_line
			(start -0.12065 0.3048)
			(end -0.67945 0.3048)
			(stroke
				(width 0.1)
				(type default)
			)
			(layer "F.Fab")
		)
		(fp_line
			(start -0.12065 0.2794)
			(end -0.12065 0.3048)
			(stroke
				(width 0.1)
				(type default)
			)
			(layer "F.Fab")
		)
		(fp_line
			(start -0.12065 -0.2794)
			(end 0.12065 -0.2794)
			(stroke
				(width 0.1)
				(type default)
			)
			(layer "F.Fab")
		)
		(fp_line
			(start -0.12065 -0.305054)
			(end -0.12065 -0.2794)
			(stroke
				(width 0.1)
				(type default)
			)
			(layer "F.Fab")
		)
		(fp_line
			(start -0.67945 0.3048)
			(end -0.67945 -0.305054)
			(stroke
				(width 0.1)
				(type default)
			)
			(layer "F.Fab")
		)
		(fp_line
			(start -0.67945 -0.305054)
			(end -0.12065 -0.305054)
			(stroke
				(width 0.1)
				(type default)
			)
			(layer "F.Fab")
		)
		(pad "1" smd circle
			(at -0.40005 0 180)
			(size 0 0)
			(layers "F.Cu" "F.Mask" "F.Paste")
			(net "SMB_VR_3V3AUX_SCL_R6")
		)
		(pad "2" smd circle
			(at 0.40005 0 180)
			(size 0 0)
			(layers "F.Cu" "F.Mask" "F.Paste")
			(net "SMB_VR_3V3AUX_SCL")
		)
	)
	(footprint ""
		(layer "F.Cu")
		(at 50.785014 -152.164542 90)
		(property "Reference" "PC443_P1_2"
			(at 0 0 90)
			(layer "F.SilkS")
			(hide yes)
			(effects
				(font
					(size 1.27 1.27)
				)
			)
		)
		(property "Value" ""
			(at 0 0 90)
			(layer "F.Fab")
			(effects
				(font
					(size 1.27 1.27)
				)
			)
		)
		(duplicate_pad_numbers_are_jumpers no)
		(fp_line
			(start 0.7874 -0.4064)
			(end 0.7874 0.4064)
			(stroke
				(width 0.1524)
				(type default)
			)
			(layer "F.SilkS")
		)
		(fp_line
			(start -0.7874 -0.4064)
			(end 0.7874 -0.4064)
			(stroke
				(width 0.1524)
				(type default)
			)
			(layer "F.SilkS")
		)
		(fp_line
			(start 0.7874 0.4064)
			(end -0.7874 0.4064)
			(stroke
				(width 0.1524)
				(type default)
			)
			(layer "F.SilkS")
		)
		(fp_line
			(start -0.7874 0.4064)
			(end -0.7874 -0.4064)
			(stroke
				(width 0.1524)
				(type default)
			)
			(layer "F.SilkS")
		)
		(fp_line
			(start -0.12065 -0.305054)
			(end -0.12065 -0.2794)
			(stroke
				(width 0.1)
				(type default)
			)
			(layer "F.Fab")
		)
		(fp_line
			(start -0.67945 -0.305054)
			(end -0.12065 -0.305054)
			(stroke
				(width 0.1)
				(type default)
			)
			(layer "F.Fab")
		)
		(fp_line
			(start 0.67945 -0.3048)
			(end 0.67945 0.3048)
			(stroke
				(width 0.1)
				(type default)
			)
			(layer "F.Fab")
		)
		(fp_line
			(start 0.12065 -0.3048)
			(end 0.67945 -0.3048)
			(stroke
				(width 0.1)
				(type default)
			)
			(layer "F.Fab")
		)
		(fp_line
			(start 0.12065 -0.2794)
			(end 0.12065 -0.3048)
			(stroke
				(width 0.1)
				(type default)
			)
			(layer "F.Fab")
		)
		(fp_line
			(start -0.12065 -0.2794)
			(end 0.12065 -0.2794)
			(stroke
				(width 0.1)
				(type default)
			)
			(layer "F.Fab")
		)
		(fp_line
			(start 0.120396 0.2794)
			(end -0.12065 0.2794)
			(stroke
				(width 0.1)
				(type default)
			)
			(layer "F.Fab")
		)
		(fp_line
			(start -0.12065 0.2794)
			(end -0.12065 0.3048)
			(stroke
				(width 0.1)
				(type default)
			)
			(layer "F.Fab")
		)
		(fp_line
			(start 0.67945 0.3048)
			(end 0.120396 0.3048)
			(stroke
				(width 0.1)
				(type default)
			)
			(layer "F.Fab")
		)
		(fp_line
			(start 0.120396 0.3048)
			(end 0.120396 0.2794)
			(stroke
				(width 0.1)
				(type default)
			)
			(layer "F.Fab")
		)
		(fp_line
			(start -0.12065 0.3048)
			(end -0.67945 0.3048)
			(stroke
				(width 0.1)
				(type default)
			)
			(layer "F.Fab")
		)
		(fp_line
			(start -0.67945 0.3048)
			(end -0.67945 -0.305054)
			(stroke
				(width 0.1)
				(type default)
			)
			(layer "F.Fab")
		)
		(pad "1" smd circle
			(at -0.40005 0 90)
			(size 0 0)
			(layers "F.Cu" "F.Mask" "F.Paste")
			(net "SW_P12V_PVCCINFAON_CPU1_FLT")
		)
		(pad "2" smd circle
			(at 0.40005 0 90)
			(size 0 0)
			(layers "F.Cu" "F.Mask" "F.Paste")
			(net "GND")
		)
	)
	(footprint ""
		(layer "F.Cu")
		(at 103.519478 -420.84879 90)
		(property "Reference" "C2275"
			(at 0 0 90)
			(layer "F.SilkS")
			(hide yes)
			(effects
				(font
					(size 1.27 1.27)
				)
			)
		)
		(property "Value" ""
			(at 0 0 90)
			(layer "F.Fab")
			(effects
				(font
					(size 1.27 1.27)
				)
			)
		)
		(duplicate_pad_numbers_are_jumpers no)
		(fp_line
			(start 0.7874 -0.4064)
			(end 0.7874 0.4064)
			(stroke
				(width 0.1524)
				(type default)
			)
			(layer "F.SilkS")
		)
		(fp_line
			(start -0.7874 -0.4064)
			(end 0.7874 -0.4064)
			(stroke
				(width 0.1524)
				(type default)
			)
			(layer "F.SilkS")
		)
		(fp_line
			(start 0.7874 0.4064)
			(end -0.7874 0.4064)
			(stroke
				(width 0.1524)
				(type default)
			)
			(layer "F.SilkS")
		)
		(fp_line
			(start -0.7874 0.4064)
			(end -0.7874 -0.4064)
			(stroke
				(width 0.1524)
				(type default)
			)
			(layer "F.SilkS")
		)
		(fp_line
			(start -0.12065 -0.305054)
			(end -0.12065 -0.2794)
			(stroke
				(width 0.1)
				(type default)
			)
			(layer "F.Fab")
		)
		(fp_line
			(start -0.67945 -0.305054)
			(end -0.12065 -0.305054)
			(stroke
				(width 0.1)
				(type default)
			)
			(layer "F.Fab")
		)
		(fp_line
			(start 0.67945 -0.3048)
			(end 0.67945 0.3048)
			(stroke
				(width 0.1)
				(type default)
			)
			(layer "F.Fab")
		)
		(fp_line
			(start 0.12065 -0.3048)
			(end 0.67945 -0.3048)
			(stroke
				(width 0.1)
				(type default)
			)
			(layer "F.Fab")
		)
		(fp_line
			(start 0.12065 -0.2794)
			(end 0.12065 -0.3048)
			(stroke
				(width 0.1)
				(type default)
			)
			(layer "F.Fab")
		)
		(fp_line
			(start -0.12065 -0.2794)
			(end 0.12065 -0.2794)
			(stroke
				(width 0.1)
				(type default)
			)
			(layer "F.Fab")
		)
		(fp_line
			(start 0.120396 0.2794)
			(end -0.12065 0.2794)
			(stroke
				(width 0.1)
				(type default)
			)
			(layer "F.Fab")
		)
		(fp_line
			(start -0.12065 0.2794)
			(end -0.12065 0.3048)
			(stroke
				(width 0.1)
				(type default)
			)
			(layer "F.Fab")
		)
		(fp_line
			(start 0.67945 0.3048)
			(end 0.120396 0.3048)
			(stroke
				(width 0.1)
				(type default)
			)
			(layer "F.Fab")
		)
		(fp_line
			(start 0.120396 0.3048)
			(end 0.120396 0.2794)
			(stroke
				(width 0.1)
				(type default)
			)
			(layer "F.Fab")
		)
		(fp_line
			(start -0.12065 0.3048)
			(end -0.67945 0.3048)
			(stroke
				(width 0.1)
				(type default)
			)
			(layer "F.Fab")
		)
		(fp_line
			(start -0.67945 0.3048)
			(end -0.67945 -0.305054)
			(stroke
				(width 0.1)
				(type default)
			)
			(layer "F.Fab")
		)
		(pad "1" smd circle
			(at -0.40005 0 90)
			(size 0 0)
			(layers "F.Cu" "F.Mask" "F.Paste")
			(net "P3V3_AUX")
		)
		(pad "2" smd circle
			(at 0.40005 0 90)
			(size 0 0)
			(layers "F.Cu" "F.Mask" "F.Paste")
			(net "GND")
		)
	)
	(footprint ""
		(layer "F.Cu")
		(at 118.542816 -258.72694 90)
		(property "Reference" "C228"
			(at 0 0 90)
			(layer "F.SilkS")
			(hide yes)
			(effects
				(font
					(size 1.27 1.27)
				)
			)
		)
		(property "Value" ""
			(at 0 0 90)
			(layer "F.Fab")
			(effects
				(font
					(size 1.27 1.27)
				)
			)
		)
		(duplicate_pad_numbers_are_jumpers no)
		(fp_line
			(start 0.7874 -0.4064)
			(end 0.7874 0.4064)
			(stroke
				(width 0.1524)
				(type default)
			)
			(layer "F.SilkS")
		)
		(fp_line
			(start -0.7874 -0.4064)
			(end 0.7874 -0.4064)
			(stroke
				(width 0.1524)
				(type default)
			)
			(layer "F.SilkS")
		)
		(fp_line
			(start 0.7874 0.4064)
			(end -0.7874 0.4064)
			(stroke
				(width 0.1524)
				(type default)
			)
			(layer "F.SilkS")
		)
		(fp_line
			(start -0.7874 0.4064)
			(end -0.7874 -0.4064)
			(stroke
				(width 0.1524)
				(type default)
			)
			(layer "F.SilkS")
		)
		(fp_line
			(start -0.12065 -0.305054)
			(end -0.12065 -0.2794)
			(stroke
				(width 0.1)
				(type default)
			)
			(layer "F.Fab")
		)
		(fp_line
			(start -0.67945 -0.305054)
			(end -0.12065 -0.305054)
			(stroke
				(width 0.1)
				(type default)
			)
			(layer "F.Fab")
		)
		(fp_line
			(start 0.67945 -0.3048)
			(end 0.67945 0.3048)
			(stroke
				(width 0.1)
				(type default)
			)
			(layer "F.Fab")
		)
		(fp_line
			(start 0.12065 -0.3048)
			(end 0.67945 -0.3048)
			(stroke
				(width 0.1)
				(type default)
			)
			(layer "F.Fab")
		)
		(fp_line
			(start 0.12065 -0.2794)
			(end 0.12065 -0.3048)
			(stroke
				(width 0.1)
				(type default)
			)
			(layer "F.Fab")
		)
		(fp_line
			(start -0.12065 -0.2794)
			(end 0.12065 -0.2794)
			(stroke
				(width 0.1)
				(type default)
			)
			(layer "F.Fab")
		)
		(fp_line
			(start 0.120396 0.2794)
			(end -0.12065 0.2794)
			(stroke
				(width 0.1)
				(type default)
			)
			(layer "F.Fab")
		)
		(fp_line
			(start -0.12065 0.2794)
			(end -0.12065 0.3048)
			(stroke
				(width 0.1)
				(type default)
			)
			(layer "F.Fab")
		)
		(fp_line
			(start 0.67945 0.3048)
			(end 0.120396 0.3048)
			(stroke
				(width 0.1)
				(type default)
			)
			(layer "F.Fab")
		)
		(fp_line
			(start 0.120396 0.3048)
			(end 0.120396 0.2794)
			(stroke
				(width 0.1)
				(type default)
			)
			(layer "F.Fab")
		)
		(fp_line
			(start -0.12065 0.3048)
			(end -0.67945 0.3048)
			(stroke
				(width 0.1)
				(type default)
			)
			(layer "F.Fab")
		)
		(fp_line
			(start -0.67945 0.3048)
			(end -0.67945 -0.305054)
			(stroke
				(width 0.1)
				(type default)
			)
			(layer "F.Fab")
		)
		(pad "1" smd circle
			(at -0.40005 0 90)
			(size 0 0)
			(layers "F.Cu" "F.Mask" "F.Paste")
			(net "PVCCIN_CPU1")
		)
		(pad "2" smd circle
			(at 0.40005 0 90)
			(size 0 0)
			(layers "F.Cu" "F.Mask" "F.Paste")
			(net "GND")
		)
	)
	(footprint ""
		(layer "F.Cu")
		(at 181.7624 -93.538548 90)
		(property "Reference" "R4589"
			(at 0 0 90)
			(layer "F.SilkS")
			(hide yes)
			(effects
				(font
					(size 1.27 1.27)
				)
			)
		)
		(property "Value" ""
			(at 0 0 90)
			(layer "F.Fab")
			(effects
				(font
					(size 1.27 1.27)
				)
			)
		)
		(duplicate_pad_numbers_are_jumpers no)
		(fp_line
			(start 0.7874 -0.4064)
			(end 0.7874 0.4064)
			(stroke
				(width 0.1524)
				(type default)
			)
			(layer "F.SilkS")
		)
		(fp_line
			(start -0.7874 -0.4064)
			(end 0.7874 -0.4064)
			(stroke
				(width 0.1524)
				(type default)
			)
			(layer "F.SilkS")
		)
		(fp_line
			(start 0.7874 0.4064)
			(end -0.7874 0.4064)
			(stroke
				(width 0.1524)
				(type default)
			)
			(layer "F.SilkS")
		)
		(fp_line
			(start -0.7874 0.4064)
			(end -0.7874 -0.4064)
			(stroke
				(width 0.1524)
				(type default)
			)
			(layer "F.SilkS")
		)
		(fp_line
			(start -0.12065 -0.305054)
			(end -0.12065 -0.2794)
			(stroke
				(width 0.1)
				(type default)
			)
			(layer "F.Fab")
		)
		(fp_line
			(start -0.67945 -0.305054)
			(end -0.12065 -0.305054)
			(stroke
				(width 0.1)
				(type default)
			)
			(layer "F.Fab")
		)
		(fp_line
			(start 0.67945 -0.3048)
			(end 0.67945 0.3048)
			(stroke
				(width 0.1)
				(type default)
			)
			(layer "F.Fab")
		)
		(fp_line
			(start 0.12065 -0.3048)
			(end 0.67945 -0.3048)
			(stroke
				(width 0.1)
				(type default)
			)
			(layer "F.Fab")
		)
		(fp_line
			(start 0.12065 -0.2794)
			(end 0.12065 -0.3048)
			(stroke
				(width 0.1)
				(type default)
			)
			(layer "F.Fab")
		)
		(fp_line
			(start -0.12065 -0.2794)
			(end 0.12065 -0.2794)
			(stroke
				(width 0.1)
				(type default)
			)
			(layer "F.Fab")
		)
		(fp_line
			(start 0.120396 0.2794)
			(end -0.12065 0.2794)
			(stroke
				(width 0.1)
				(type default)
			)
			(layer "F.Fab")
		)
		(fp_line
			(start -0.12065 0.2794)
			(end -0.12065 0.3048)
			(stroke
				(width 0.1)
				(type default)
			)
			(layer "F.Fab")
		)
		(fp_line
			(start 0.67945 0.3048)
			(end 0.120396 0.3048)
			(stroke
				(width 0.1)
				(type default)
			)
			(layer "F.Fab")
		)
		(fp_line
			(start 0.120396 0.3048)
			(end 0.120396 0.2794)
			(stroke
				(width 0.1)
				(type default)
			)
			(layer "F.Fab")
		)
		(fp_line
			(start -0.12065 0.3048)
			(end -0.67945 0.3048)
			(stroke
				(width 0.1)
				(type default)
			)
			(layer "F.Fab")
		)
		(fp_line
			(start -0.67945 0.3048)
			(end -0.67945 -0.305054)
			(stroke
				(width 0.1)
				(type default)
			)
			(layer "F.Fab")
		)
		(pad "1" smd rect
			(at -0.40005 0 270)
			(size 0.4572 0.508)
			(layers "F.Cu" "F.Mask" "F.Paste")
			(net "P3V3_AUX")
		)
		(pad "2" smd rect
			(at 0.40005 0 270)
			(size 0.4572 0.508)
			(layers "F.Cu" "F.Mask" "F.Paste")
			(net "FAB_BMC_REV_ID1")
		)
	)
	(footprint ""
		(layer "F.Cu")
		(at 107.2769 -252.956568 -90)
		(property "Reference" "C275"
			(at 0 0 270)
			(layer "F.SilkS")
			(hide yes)
			(effects
				(font
					(size 1.27 1.27)
				)
			)
		)
		(property "Value" ""
			(at 0 0 270)
			(layer "F.Fab")
			(effects
				(font
					(size 1.27 1.27)
				)
			)
		)
		(duplicate_pad_numbers_are_jumpers no)
		(fp_line
			(start -0.7874 0.4064)
			(end -0.7874 -0.4064)
			(stroke
				(width 0.1524)
				(type default)
			)
			(layer "F.SilkS")
		)
		(fp_line
			(start 0.7874 0.4064)
			(end -0.7874 0.4064)
			(stroke
				(width 0.1524)
				(type default)
			)
			(layer "F.SilkS")
		)
		(fp_line
			(start -0.7874 -0.4064)
			(end 0.7874 -0.4064)
			(stroke
				(width 0.1524)
				(type default)
			)
			(layer "F.SilkS")
		)
		(fp_line
			(start 0.7874 -0.4064)
			(end 0.7874 0.4064)
			(stroke
				(width 0.1524)
				(type default)
			)
			(layer "F.SilkS")
		)
		(fp_line
			(start -0.67945 0.3048)
			(end -0.67945 -0.305054)
			(stroke
				(width 0.1)
				(type default)
			)
			(layer "F.Fab")
		)
		(fp_line
			(start -0.12065 0.3048)
			(end -0.67945 0.3048)
			(stroke
				(width 0.1)
				(type default)
			)
			(layer "F.Fab")
		)
		(fp_line
			(start 0.120396 0.3048)
			(end 0.120396 0.2794)
			(stroke
				(width 0.1)
				(type default)
			)
			(layer "F.Fab")
		)
		(fp_line
			(start 0.67945 0.3048)
			(end 0.120396 0.3048)
			(stroke
				(width 0.1)
				(type default)
			)
			(layer "F.Fab")
		)
		(fp_line
			(start -0.12065 0.2794)
			(end -0.12065 0.3048)
			(stroke
				(width 0.1)
				(type default)
			)
			(layer "F.Fab")
		)
		(fp_line
			(start 0.120396 0.2794)
			(end -0.12065 0.2794)
			(stroke
				(width 0.1)
				(type default)
			)
			(layer "F.Fab")
		)
		(fp_line
			(start -0.12065 -0.2794)
			(end 0.12065 -0.2794)
			(stroke
				(width 0.1)
				(type default)
			)
			(layer "F.Fab")
		)
		(fp_line
			(start 0.12065 -0.2794)
			(end 0.12065 -0.3048)
			(stroke
				(width 0.1)
				(type default)
			)
			(layer "F.Fab")
		)
		(fp_line
			(start 0.12065 -0.3048)
			(end 0.67945 -0.3048)
			(stroke
				(width 0.1)
				(type default)
			)
			(layer "F.Fab")
		)
		(fp_line
			(start 0.67945 -0.3048)
			(end 0.67945 0.3048)
			(stroke
				(width 0.1)
				(type default)
			)
			(layer "F.Fab")
		)
		(fp_line
			(start -0.67945 -0.305054)
			(end -0.12065 -0.305054)
			(stroke
				(width 0.1)
				(type default)
			)
			(layer "F.Fab")
		)
		(fp_line
			(start -0.12065 -0.305054)
			(end -0.12065 -0.2794)
			(stroke
				(width 0.1)
				(type default)
			)
			(layer "F.Fab")
		)
		(pad "1" smd circle
			(at -0.40005 0 270)
			(size 0 0)
			(layers "F.Cu" "F.Mask" "F.Paste")
			(net "PVCCIN_CPU1")
		)
		(pad "2" smd circle
			(at 0.40005 0 270)
			(size 0 0)
			(layers "F.Cu" "F.Mask" "F.Paste")
			(net "GND")
		)
	)
)
